(kicad_pcb
	(version 20260206)
	(generator "pcbnew")
	(generator_version "10.0")
	(general
		(thickness 1.6)
		(legacy_teardrops no)
	)
	(paper "A4")
	(title_block
		(title "01162023_DA0F0TEBIF0_F0T_Expander_BD_F_brd_V02_OCP.brd")
		(comment 1 "Grand Teton / footprints 6232-6238 of 9728")
	)
	(layers
		(0 "F.Cu" signal "TOP")
		(4 "In1.Cu" signal "GND")
		(6 "In2.Cu" signal "VCC")
		(8 "In3.Cu" signal "VCC1")
		(10 "In4.Cu" signal "GND1")
		(12 "In5.Cu" signal "IN1")
		(14 "In6.Cu" signal "GND2")
		(16 "In7.Cu" signal "IN2")
		(18 "In8.Cu" signal "GND3")
		(20 "In9.Cu" signal "IN3")
		(22 "In10.Cu" signal "GND4")
		(24 "In11.Cu" signal "IN4")
		(26 "In12.Cu" signal "GND5")
		(28 "In13.Cu" signal "IN5")
		(30 "In14.Cu" signal "GND6")
		(32 "In15.Cu" signal "IN6")
		(34 "In16.Cu" signal "GND7")
		(2 "B.Cu" signal "BOTTOM")
		(9 "F.Adhes" user "F.Adhesive")
		(11 "B.Adhes" user "B.Adhesive")
		(13 "F.Paste" user "Package Geometry/Pastemask Top")
		(15 "B.Paste" user "Package Geometry/Pastemask Bottom")
		(5 "F.SilkS" user "Ref Des/Silkscreen Top")
		(7 "B.SilkS" user "Ref Des/Silkscreen Bottom")
		(1 "F.Mask" user "Board Geometry/Soldermask Top")
		(3 "B.Mask" user "Board Geometry/Soldermask Bottom")
		(17 "Dwgs.User" user "User.Drawings")
		(19 "Cmts.User" user "User.Comments")
		(21 "Eco1.User" user "User.Eco1")
		(23 "Eco2.User" user "User.Eco2")
		(25 "Edge.Cuts" user "Board Geometry/Outline")
		(27 "Margin" user)
		(31 "F.CrtYd" user "Package Geometry/Place Bound Top")
		(29 "B.CrtYd" user "Package Geometry/Place Bound Bottom")
		(35 "F.Fab" user "Ref Des/Assembly Top")
		(33 "B.Fab" user "Ref Des/Assembly Bottom")
	)
	(footprint ""
		(layer "F.Cu")
		(at 354.05441 -48.21809)
		(property "Reference" "PD69"
			(at -3.48361 2.29616 0)
			(unlocked yes)
			(layer "F.SilkS")
			(effects
				(font
					(size 0.7874 0.5842)
					(thickness 0.1524)
				)
				(justify left)
			)
		)
		(property "Value" ""
			(at 0 0 0)
			(layer "F.Fab")
			(effects
				(font
					(size 1.27 1.27)
				)
			)
		)
		(duplicate_pad_numbers_are_jumpers no)
		(fp_line
			(start -3.400044 -1.459992)
			(end 4.107942 -1.459992)
			(stroke
				(width 0.1524)
				(type default)
			)
			(layer "F.SilkS")
		)
		(fp_line
			(start -3.400044 1.459992)
			(end -3.400044 -1.459992)
			(stroke
				(width 0.1524)
				(type default)
			)
			(layer "F.SilkS")
		)
		(fp_line
			(start 4.107942 -1.459992)
			(end 4.107942 1.459992)
			(stroke
				(width 0.1524)
				(type default)
			)
			(layer "F.SilkS")
		)
		(fp_line
			(start 4.107942 1.459992)
			(end -3.400044 1.459992)
			(stroke
				(width 0.1524)
				(type default)
			)
			(layer "F.SilkS")
		)
		(fp_poly
			(pts
				(xy 4.107942 -1.459992) (xy 4.107942 1.459992) (xy 3.308096 1.459992) (xy 3.308096 -1.459992)
			)
			(stroke
				(width 0)
				(type default)
			)
			(fill yes)
			(layer "F.SilkS")
		)
		(fp_line
			(start -2.29997 -1.459992)
			(end 2.29997 -1.459992)
			(stroke
				(width 0.1)
				(type default)
			)
			(layer "F.Fab")
		)
		(fp_line
			(start -2.29997 1.459992)
			(end -2.29997 -1.459992)
			(stroke
				(width 0.1)
				(type default)
			)
			(layer "F.Fab")
		)
		(fp_line
			(start 2.29997 -1.459992)
			(end 2.29997 1.459992)
			(stroke
				(width 0.1)
				(type default)
			)
			(layer "F.Fab")
		)
		(fp_line
			(start 2.29997 1.459992)
			(end -2.29997 1.459992)
			(stroke
				(width 0.1)
				(type default)
			)
			(layer "F.Fab")
		)
		(fp_text user "+"
			(at -4.7752 -0.12065 0)
			(unlocked yes)
			(layer "F.SilkS")
			(effects
				(font
					(size 1.905 1.4224)
					(thickness 0.1524)
				)
				(justify left)
			)
		)
		(fp_text user "-"
			(at 5.4102 0.29845 180)
			(unlocked yes)
			(layer "F.SilkS")
			(effects
				(font
					(size 1.905 1.4224)
					(thickness 0.1524)
				)
				(justify left)
			)
		)
		(fp_text user "+"
			(at -4.7752 -0.12065 0)
			(unlocked yes)
			(layer "F.Fab")
			(effects
				(font
					(size 1.905 1.4224)
					(thickness 0.1524)
				)
				(justify left)
			)
		)
		(fp_text user "-"
			(at 5.4102 0.29845 180)
			(unlocked yes)
			(layer "F.Fab")
			(effects
				(font
					(size 1.905 1.4224)
					(thickness 0.1524)
				)
				(justify left)
			)
		)
		(pad "A" smd rect
			(at -1.999996 0 90)
			(size 1.7018 2.5146)
			(layers "F.Cu" "F.Mask" "F.Paste")
			(net "GND")
		)
		(pad "C" smd rect
			(at 1.999996 0 90)
			(size 1.7018 2.5146)
			(layers "F.Cu" "F.Mask" "F.Paste")
			(net "P3V3_SSD12")
		)
	)
	(footprint ""
		(layer "F.Cu")
		(at 335.154524 -350.098614 90)
		(property "Reference" "C572"
			(at 0 0 90)
			(layer "F.SilkS")
			(hide yes)
			(effects
				(font
					(size 1.27 1.27)
				)
			)
		)
		(property "Value" ""
			(at 0 0 90)
			(layer "F.Fab")
			(effects
				(font
					(size 1.27 1.27)
				)
			)
		)
		(duplicate_pad_numbers_are_jumpers no)
		(fp_line
			(start 0.299974 -0.150114)
			(end 0.299974 0.150114)
			(stroke
				(width 0.1)
				(type default)
			)
			(layer "F.Fab")
		)
		(fp_line
			(start -0.299974 -0.150114)
			(end 0.299974 -0.150114)
			(stroke
				(width 0.1)
				(type default)
			)
			(layer "F.Fab")
		)
		(fp_line
			(start 0.299974 0.150114)
			(end -0.299974 0.150114)
			(stroke
				(width 0.1)
				(type default)
			)
			(layer "F.Fab")
		)
		(fp_line
			(start -0.299974 0.150114)
			(end -0.299974 -0.150114)
			(stroke
				(width 0.1)
				(type default)
			)
			(layer "F.Fab")
		)
		(pad "1" smd rect
			(at -0.2667 0 90)
			(size 0.3048 0.381)
			(layers "F.Cu" "F.Mask" "F.Paste")
			(net "P5E_PEX2_STN6_TX_DN<101>")
		)
		(pad "2" smd rect
			(at 0.2667 0 90)
			(size 0.3048 0.381)
			(layers "F.Cu" "F.Mask" "F.Paste")
			(net "P5E_PEX2_STN6_TX_C_DN<101>")
		)
	)
	(footprint ""
		(layer "F.Cu")
		(at 362.268262 -357.956358 -90)
		(property "Reference" "R6448"
			(at 0 0 270)
			(layer "F.SilkS")
			(hide yes)
			(effects
				(font
					(size 1.27 1.27)
				)
			)
		)
		(property "Value" ""
			(at 0 0 270)
			(layer "F.Fab")
			(effects
				(font
					(size 1.27 1.27)
				)
			)
		)
		(duplicate_pad_numbers_are_jumpers no)
		(fp_line
			(start -0.7874 0.4064)
			(end -0.7874 -0.4064)
			(stroke
				(width 0.1524)
				(type default)
			)
			(layer "F.SilkS")
		)
		(fp_line
			(start 0.7874 0.4064)
			(end -0.7874 0.4064)
			(stroke
				(width 0.1524)
				(type default)
			)
			(layer "F.SilkS")
		)
		(fp_line
			(start -0.7874 -0.4064)
			(end 0.7874 -0.4064)
			(stroke
				(width 0.1524)
				(type default)
			)
			(layer "F.SilkS")
		)
		(fp_line
			(start 0.7874 -0.4064)
			(end 0.7874 0.4064)
			(stroke
				(width 0.1524)
				(type default)
			)
			(layer "F.SilkS")
		)
		(fp_line
			(start -0.67945 0.3048)
			(end -0.67945 -0.305054)
			(stroke
				(width 0.1)
				(type default)
			)
			(layer "F.Fab")
		)
		(fp_line
			(start -0.12065 0.3048)
			(end -0.67945 0.3048)
			(stroke
				(width 0.1)
				(type default)
			)
			(layer "F.Fab")
		)
		(fp_line
			(start 0.120396 0.3048)
			(end 0.120396 0.2794)
			(stroke
				(width 0.1)
				(type default)
			)
			(layer "F.Fab")
		)
		(fp_line
			(start 0.67945 0.3048)
			(end 0.120396 0.3048)
			(stroke
				(width 0.1)
				(type default)
			)
			(layer "F.Fab")
		)
		(fp_line
			(start -0.12065 0.2794)
			(end -0.12065 0.3048)
			(stroke
				(width 0.1)
				(type default)
			)
			(layer "F.Fab")
		)
		(fp_line
			(start 0.120396 0.2794)
			(end -0.12065 0.2794)
			(stroke
				(width 0.1)
				(type default)
			)
			(layer "F.Fab")
		)
		(fp_line
			(start -0.12065 -0.2794)
			(end 0.12065 -0.2794)
			(stroke
				(width 0.1)
				(type default)
			)
			(layer "F.Fab")
		)
		(fp_line
			(start 0.12065 -0.2794)
			(end 0.12065 -0.3048)
			(stroke
				(width 0.1)
				(type default)
			)
			(layer "F.Fab")
		)
		(fp_line
			(start 0.12065 -0.3048)
			(end 0.67945 -0.3048)
			(stroke
				(width 0.1)
				(type default)
			)
			(layer "F.Fab")
		)
		(fp_line
			(start 0.67945 -0.3048)
			(end 0.67945 0.3048)
			(stroke
				(width 0.1)
				(type default)
			)
			(layer "F.Fab")
		)
		(fp_line
			(start -0.67945 -0.305054)
			(end -0.12065 -0.305054)
			(stroke
				(width 0.1)
				(type default)
			)
			(layer "F.Fab")
		)
		(fp_line
			(start -0.12065 -0.305054)
			(end -0.12065 -0.2794)
			(stroke
				(width 0.1)
				(type default)
			)
			(layer "F.Fab")
		)
		(pad "1" smd circle
			(at -0.40005 0 270)
			(size 0 0)
			(layers "F.Cu" "F.Mask" "F.Paste")
			(net "MB_SWB_PWR_EN")
		)
		(pad "2" smd circle
			(at 0.40005 0 270)
			(size 0 0)
			(layers "F.Cu" "F.Mask" "F.Paste")
			(net "GND")
		)
	)
	(footprint ""
		(layer "F.Cu")
		(at 237.494064 -34.248852)
		(property "Reference" "R5683"
			(at 0 0 0)
			(layer "F.SilkS")
			(hide yes)
			(effects
				(font
					(size 1.27 1.27)
				)
			)
		)
		(property "Value" ""
			(at 0 0 0)
			(layer "F.Fab")
			(effects
				(font
					(size 1.27 1.27)
				)
			)
		)
		(duplicate_pad_numbers_are_jumpers no)
		(fp_line
			(start -0.7874 -0.4064)
			(end 0.7874 -0.4064)
			(stroke
				(width 0.1524)
				(type default)
			)
			(layer "F.SilkS")
		)
		(fp_line
			(start -0.7874 0.4064)
			(end -0.7874 -0.4064)
			(stroke
				(width 0.1524)
				(type default)
			)
			(layer "F.SilkS")
		)
		(fp_line
			(start 0.7874 -0.4064)
			(end 0.7874 0.4064)
			(stroke
				(width 0.1524)
				(type default)
			)
			(layer "F.SilkS")
		)
		(fp_line
			(start 0.7874 0.4064)
			(end -0.7874 0.4064)
			(stroke
				(width 0.1524)
				(type default)
			)
			(layer "F.SilkS")
		)
		(fp_line
			(start -0.67945 -0.305054)
			(end -0.12065 -0.305054)
			(stroke
				(width 0.1)
				(type default)
			)
			(layer "F.Fab")
		)
		(fp_line
			(start -0.67945 0.3048)
			(end -0.67945 -0.305054)
			(stroke
				(width 0.1)
				(type default)
			)
			(layer "F.Fab")
		)
		(fp_line
			(start -0.12065 -0.305054)
			(end -0.12065 -0.2794)
			(stroke
				(width 0.1)
				(type default)
			)
			(layer "F.Fab")
		)
		(fp_line
			(start -0.12065 -0.2794)
			(end 0.12065 -0.2794)
			(stroke
				(width 0.1)
				(type default)
			)
			(layer "F.Fab")
		)
		(fp_line
			(start -0.12065 0.2794)
			(end -0.12065 0.3048)
			(stroke
				(width 0.1)
				(type default)
			)
			(layer "F.Fab")
		)
		(fp_line
			(start -0.12065 0.3048)
			(end -0.67945 0.3048)
			(stroke
				(width 0.1)
				(type default)
			)
			(layer "F.Fab")
		)
		(fp_line
			(start 0.120396 0.2794)
			(end -0.12065 0.2794)
			(stroke
				(width 0.1)
				(type default)
			)
			(layer "F.Fab")
		)
		(fp_line
			(start 0.120396 0.3048)
			(end 0.120396 0.2794)
			(stroke
				(width 0.1)
				(type default)
			)
			(layer "F.Fab")
		)
		(fp_line
			(start 0.12065 -0.3048)
			(end 0.67945 -0.3048)
			(stroke
				(width 0.1)
				(type default)
			)
			(layer "F.Fab")
		)
		(fp_line
			(start 0.12065 -0.2794)
			(end 0.12065 -0.3048)
			(stroke
				(width 0.1)
				(type default)
			)
			(layer "F.Fab")
		)
		(fp_line
			(start 0.67945 -0.3048)
			(end 0.67945 0.3048)
			(stroke
				(width 0.1)
				(type default)
			)
			(layer "F.Fab")
		)
		(fp_line
			(start 0.67945 0.3048)
			(end 0.120396 0.3048)
			(stroke
				(width 0.1)
				(type default)
			)
			(layer "F.Fab")
		)
		(pad "1" smd circle
			(at -0.40005 0)
			(size 0 0)
			(layers "F.Cu" "F.Mask" "F.Paste")
			(net "RST_SMB_SSD8_ISO_N")
		)
		(pad "2" smd circle
			(at 0.40005 0)
			(size 0 0)
			(layers "F.Cu" "F.Mask" "F.Paste")
			(net "P3V3_SSD8")
		)
	)
	(footprint ""
		(layer "F.Cu")
		(at 292.378892 -59.577986 -90)
		(property "Reference" "R898"
			(at 0 0 270)
			(layer "F.SilkS")
			(hide yes)
			(effects
				(font
					(size 1.27 1.27)
				)
			)
		)
		(property "Value" ""
			(at 0 0 270)
			(layer "F.Fab")
			(effects
				(font
					(size 1.27 1.27)
				)
			)
		)
		(duplicate_pad_numbers_are_jumpers no)
		(fp_line
			(start -0.7874 0.4064)
			(end -0.7874 -0.4064)
			(stroke
				(width 0.1524)
				(type default)
			)
			(layer "F.SilkS")
		)
		(fp_line
			(start 0.7874 0.4064)
			(end -0.7874 0.4064)
			(stroke
				(width 0.1524)
				(type default)
			)
			(layer "F.SilkS")
		)
		(fp_line
			(start -0.7874 -0.4064)
			(end 0.7874 -0.4064)
			(stroke
				(width 0.1524)
				(type default)
			)
			(layer "F.SilkS")
		)
		(fp_line
			(start 0.7874 -0.4064)
			(end 0.7874 0.4064)
			(stroke
				(width 0.1524)
				(type default)
			)
			(layer "F.SilkS")
		)
		(fp_line
			(start -0.67945 0.3048)
			(end -0.67945 -0.305054)
			(stroke
				(width 0.1)
				(type default)
			)
			(layer "F.Fab")
		)
		(fp_line
			(start -0.12065 0.3048)
			(end -0.67945 0.3048)
			(stroke
				(width 0.1)
				(type default)
			)
			(layer "F.Fab")
		)
		(fp_line
			(start 0.120396 0.3048)
			(end 0.120396 0.2794)
			(stroke
				(width 0.1)
				(type default)
			)
			(layer "F.Fab")
		)
		(fp_line
			(start 0.67945 0.3048)
			(end 0.120396 0.3048)
			(stroke
				(width 0.1)
				(type default)
			)
			(layer "F.Fab")
		)
		(fp_line
			(start -0.12065 0.2794)
			(end -0.12065 0.3048)
			(stroke
				(width 0.1)
				(type default)
			)
			(layer "F.Fab")
		)
		(fp_line
			(start 0.120396 0.2794)
			(end -0.12065 0.2794)
			(stroke
				(width 0.1)
				(type default)
			)
			(layer "F.Fab")
		)
		(fp_line
			(start -0.12065 -0.2794)
			(end 0.12065 -0.2794)
			(stroke
				(width 0.1)
				(type default)
			)
			(layer "F.Fab")
		)
		(fp_line
			(start 0.12065 -0.2794)
			(end 0.12065 -0.3048)
			(stroke
				(width 0.1)
				(type default)
			)
			(layer "F.Fab")
		)
		(fp_line
			(start 0.12065 -0.3048)
			(end 0.67945 -0.3048)
			(stroke
				(width 0.1)
				(type default)
			)
			(layer "F.Fab")
		)
		(fp_line
			(start 0.67945 -0.3048)
			(end 0.67945 0.3048)
			(stroke
				(width 0.1)
				(type default)
			)
			(layer "F.Fab")
		)
		(fp_line
			(start -0.67945 -0.305054)
			(end -0.12065 -0.305054)
			(stroke
				(width 0.1)
				(type default)
			)
			(layer "F.Fab")
		)
		(fp_line
			(start -0.12065 -0.305054)
			(end -0.12065 -0.2794)
			(stroke
				(width 0.1)
				(type default)
			)
			(layer "F.Fab")
		)
		(pad "1" smd circle
			(at -0.40005 0 270)
			(size 0 0)
			(layers "F.Cu" "F.Mask" "F.Paste")
			(net "P3V3_SSD10")
		)
		(pad "2" smd circle
			(at 0.40005 0 270)
			(size 0 0)
			(layers "F.Cu" "F.Mask" "F.Paste")
			(net "PWRGD_P3V3_SSD10")
		)
	)
	(footprint ""
		(layer "F.Cu")
		(at 112.88776 -129.285746 180)
		(property "Reference" "PC298"
			(at 0 0 180)
			(layer "F.SilkS")
			(hide yes)
			(effects
				(font
					(size 1.27 1.27)
				)
			)
		)
		(property "Value" ""
			(at 0 0 180)
			(layer "F.Fab")
			(effects
				(font
					(size 1.27 1.27)
				)
			)
		)
		(duplicate_pad_numbers_are_jumpers no)
		(fp_line
			(start 0.7874 0.4064)
			(end -0.7874 0.4064)
			(stroke
				(width 0.1524)
				(type default)
			)
			(layer "F.SilkS")
		)
		(fp_line
			(start 0.7874 -0.4064)
			(end 0.7874 0.4064)
			(stroke
				(width 0.1524)
				(type default)
			)
			(layer "F.SilkS")
		)
		(fp_line
			(start -0.7874 0.4064)
			(end -0.7874 -0.4064)
			(stroke
				(width 0.1524)
				(type default)
			)
			(layer "F.SilkS")
		)
		(fp_line
			(start -0.7874 -0.4064)
			(end 0.7874 -0.4064)
			(stroke
				(width 0.1524)
				(type default)
			)
			(layer "F.SilkS")
		)
		(fp_line
			(start 0.67945 0.3048)
			(end 0.120396 0.3048)
			(stroke
				(width 0.1)
				(type default)
			)
			(layer "F.Fab")
		)
		(fp_line
			(start 0.67945 -0.3048)
			(end 0.67945 0.3048)
			(stroke
				(width 0.1)
				(type default)
			)
			(layer "F.Fab")
		)
		(fp_line
			(start 0.12065 -0.2794)
			(end 0.12065 -0.3048)
			(stroke
				(width 0.1)
				(type default)
			)
			(layer "F.Fab")
		)
		(fp_line
			(start 0.12065 -0.3048)
			(end 0.67945 -0.3048)
			(stroke
				(width 0.1)
				(type default)
			)
			(layer "F.Fab")
		)
		(fp_line
			(start 0.120396 0.3048)
			(end 0.120396 0.2794)
			(stroke
				(width 0.1)
				(type default)
			)
			(layer "F.Fab")
		)
		(fp_line
			(start 0.120396 0.2794)
			(end -0.12065 0.2794)
			(stroke
				(width 0.1)
				(type default)
			)
			(layer "F.Fab")
		)
		(fp_line
			(start -0.12065 0.3048)
			(end -0.67945 0.3048)
			(stroke
				(width 0.1)
				(type default)
			)
			(layer "F.Fab")
		)
		(fp_line
			(start -0.12065 0.2794)
			(end -0.12065 0.3048)
			(stroke
				(width 0.1)
				(type default)
			)
			(layer "F.Fab")
		)
		(fp_line
			(start -0.12065 -0.2794)
			(end 0.12065 -0.2794)
			(stroke
				(width 0.1)
				(type default)
			)
			(layer "F.Fab")
		)
		(fp_line
			(start -0.12065 -0.305054)
			(end -0.12065 -0.2794)
			(stroke
				(width 0.1)
				(type default)
			)
			(layer "F.Fab")
		)
		(fp_line
			(start -0.67945 0.3048)
			(end -0.67945 -0.305054)
			(stroke
				(width 0.1)
				(type default)
			)
			(layer "F.Fab")
		)
		(fp_line
			(start -0.67945 -0.305054)
			(end -0.12065 -0.305054)
			(stroke
				(width 0.1)
				(type default)
			)
			(layer "F.Fab")
		)
		(pad "1" smd circle
			(at -0.40005 0 180)
			(size 0 0)
			(layers "F.Cu" "F.Mask" "F.Paste")
			(net "P3V3_AUX")
		)
		(pad "2" smd circle
			(at 0.40005 0 180)
			(size 0 0)
			(layers "F.Cu" "F.Mask" "F.Paste")
			(net "GND")
		)
	)
	(footprint ""
		(layer "F.Cu")
		(at 178.591718 -161.881566 90)
		(property "Reference" "Q120"
			(at -0.032766 -2.009648 90)
			(unlocked yes)
			(layer "F.SilkS")
			(effects
				(font
					(size 0.7874 0.5842)
					(thickness 0.1524)
				)
			)
		)
		(property "Value" ""
			(at 0 0 90)
			(layer "F.Fab")
			(effects
				(font
					(size 1.27 1.27)
				)
			)
		)
		(duplicate_pad_numbers_are_jumpers no)
		(fp_line
			(start 1.376172 -1.199896)
			(end 1.376172 1.199896)
			(stroke
				(width 0.1524)
				(type default)
			)
			(layer "F.SilkS")
		)
		(fp_line
			(start 0.508 -1.199896)
			(end 1.376172 -1.199896)
			(stroke
				(width 0.1524)
				(type default)
			)
			(layer "F.SilkS")
		)
		(fp_line
			(start -0.508 -1.199896)
			(end 0 -0.762)
			(stroke
				(width 0.1524)
				(type default)
			)
			(layer "F.SilkS")
		)
		(fp_line
			(start -1.376172 -1.199896)
			(end -0.508 -1.199896)
			(stroke
				(width 0.1524)
				(type default)
			)
			(layer "F.SilkS")
		)
		(fp_line
			(start 0 -0.762)
			(end 0.508 -1.199896)
			(stroke
				(width 0.1524)
				(type default)
			)
			(layer "F.SilkS")
		)
		(fp_line
			(start 1.376172 1.199896)
			(end -1.376172 1.199896)
			(stroke
				(width 0.1524)
				(type default)
			)
			(layer "F.SilkS")
		)
		(fp_line
			(start -1.376172 1.199896)
			(end -1.376172 -1.199896)
			(stroke
				(width 0.1524)
				(type default)
			)
			(layer "F.SilkS")
		)
		(fp_poly
			(pts
				(xy -1.537462 -1.195578) (xy -1.806956 -2.003806) (xy -2.34569 -1.465072)
			)
			(stroke
				(width 0)
				(type default)
			)
			(fill yes)
			(layer "F.SilkS")
		)
		(fp_line
			(start 0.674878 -1.100074)
			(end 0.674878 1.100074)
			(stroke
				(width 0.1)
				(type default)
			)
			(layer "F.Fab")
		)
		(fp_line
			(start -0.674878 -1.100074)
			(end 0.674878 -1.100074)
			(stroke
				(width 0.1)
				(type default)
			)
			(layer "F.Fab")
		)
		(fp_line
			(start 0.674878 1.100074)
			(end -0.674878 1.100074)
			(stroke
				(width 0.1)
				(type default)
			)
			(layer "F.Fab")
		)
		(fp_line
			(start -0.674878 1.100074)
			(end -0.674878 -1.100074)
			(stroke
				(width 0.1)
				(type default)
			)
			(layer "F.Fab")
		)
		(fp_poly
			(pts
				(xy -1.4605 -0.7493) (xy -2.2225 -1.1303) (xy -2.2225 -0.3683)
			)
			(stroke
				(width 0)
				(type default)
			)
			(fill yes)
			(layer "F.Fab")
		)
		(pad "1" smd rect
			(at -0.899922 -0.750062)
			(size 0.6096 0.6096)
			(layers "F.Cu" "F.Mask" "F.Paste")
			(net "GND")
		)
		(pad "2" smd rect
			(at -0.899922 0)
			(size 0.4064 0.6096)
			(layers "F.Cu" "F.Mask" "F.Paste")
			(net "FM_SYS_THROTTLE_NIC2")
		)
		(pad "3" smd rect
			(at -0.899922 0.750062)
			(size 0.6096 0.6096)
			(layers "F.Cu" "F.Mask" "F.Paste")
			(net "NIC3_PWRBRK_N")
		)
		(pad "4" smd rect
			(at 0.899922 0.750062)
			(size 0.6096 0.6096)
			(layers "F.Cu" "F.Mask" "F.Paste")
			(net "GND")
		)
		(pad "5" smd rect
			(at 0.899922 0)
			(size 0.4064 0.6096)
			(layers "F.Cu" "F.Mask" "F.Paste")
			(net "FM_SYS_THROTTLE_NIC3")
		)
		(pad "6" smd rect
			(at 0.899922 -0.750062)
			(size 0.6096 0.6096)
			(layers "F.Cu" "F.Mask" "F.Paste")
			(net "NIC2_PWRBRK_N")
		)
	)
)
